# T6G (Grand Teton) — schematic netlist excerpt (pin names and nets, part order shuffled) for the footprints in the layout excerpt that follows; sources: Cadence DE-HDL packaged netlist, KiCad conversion of 04192023_DAF0TMB3IC0_F0TG_MB_C_brd_V02_OCP.brd

PC182  Q_CAP  560PF 50V 10% EMPTY  pkg C0402  page 196 : A = SW_PVDDCR_CPU0_P0_SW6 ; B = SW_PVDDCR_CPU0_P0_SW6_RC
PC6006  Q_CAP  0.01UF 25V 10% EMPTY  pkg C0402  page 226 : A = PVDD18_S5_P1_FB_RC ; B = PVDD18_SS_P1_RGND

(kicad_pcb
	(version 20260206)
	(generator "pcbnew")
	(generator_version "10.0")
	(general
		(thickness 1.6)
		(legacy_teardrops no)
	)
	(paper "A4")
	(title_block
		(title "04192023_DAF0TMB3IC0_F0TG_MB_C_brd_V02_OCP.brd")
		(comment 1 "Grand Teton / footprints 4402-4403 of 8354")
	)
	(layers
		(0 "F.Cu" signal "TOP")
		(4 "In1.Cu" signal "GND")
		(6 "In2.Cu" signal "IN1")
		(8 "In3.Cu" signal "GND1")
		(10 "In4.Cu" signal "IN2")
		(12 "In5.Cu" signal "GND2")
		(14 "In6.Cu" signal "IN3")
		(16 "In7.Cu" signal "GND3")
		(18 "In8.Cu" signal "VCC")
		(20 "In9.Cu" signal "VCC1")
		(22 "In10.Cu" signal "GND4")
		(24 "In11.Cu" signal "IN4")
		(26 "In12.Cu" signal "GND5")
		(28 "In13.Cu" signal "IN5")
		(30 "In14.Cu" signal "GND6")
		(32 "In15.Cu" signal "IN6")
		(34 "In16.Cu" signal "GND7")
		(2 "B.Cu" signal "BOTTOM")
		(9 "F.Adhes" user "F.Adhesive")
		(11 "B.Adhes" user "B.Adhesive")
		(13 "F.Paste" user "Package Geometry/Pastemask Top")
		(15 "B.Paste" user "Package Geometry/Pastemask Bottom")
		(5 "F.SilkS" user "Ref Des/Silkscreen Top")
		(7 "B.SilkS" user "Ref Des/Silkscreen Bottom")
		(1 "F.Mask" user "Board Geometry/Soldermask Top")
		(3 "B.Mask" user "Board Geometry/Soldermask Bottom")
		(17 "Dwgs.User" user "User.Drawings")
		(19 "Cmts.User" user "User.Comments")
		(21 "Eco1.User" user "User.Eco1")
		(23 "Eco2.User" user "User.Eco2")
		(25 "Edge.Cuts" user "Board Geometry/Outline")
		(27 "Margin" user)
		(31 "F.CrtYd" user "Package Geometry/Place Bound Top")
		(29 "B.CrtYd" user "Package Geometry/Place Bound Bottom")
		(35 "F.Fab" user "Ref Des/Assembly Top")
		(33 "B.Fab" user "Ref Des/Assembly Bottom")
	)
	(footprint ""
		(layer "F.Cu")
		(at 351.4217 -164.14369)
		(property "Reference" "PC182"
			(at 0 0 0)
			(layer "F.SilkS")
			(hide yes)
			(effects
				(font
					(size 1.27 1.27)
				)
			)
		)
		(property "Value" ""
			(at 0 0 0)
			(layer "F.Fab")
			(effects
				(font
					(size 1.27 1.27)
				)
			)
		)
		(duplicate_pad_numbers_are_jumpers no)
		(fp_line
			(start -0.7874 -0.4064)
			(end 0.7874 -0.4064)
			(stroke
				(width 0.1524)
				(type default)
			)
			(layer "F.SilkS")
		)
		(fp_line
			(start -0.7874 0.4064)
			(end -0.7874 -0.4064)
			(stroke
				(width 0.1524)
				(type default)
			)
			(layer "F.SilkS")
		)
		(fp_line
			(start 0.7874 -0.4064)
			(end 0.7874 0.4064)
			(stroke
				(width 0.1524)
				(type default)
			)
			(layer "F.SilkS")
		)
		(fp_line
			(start 0.7874 0.4064)
			(end -0.7874 0.4064)
			(stroke
				(width 0.1524)
				(type default)
			)
			(layer "F.SilkS")
		)
		(fp_line
			(start -0.67945 -0.305054)
			(end -0.12065 -0.305054)
			(stroke
				(width 0.1)
				(type default)
			)
			(layer "F.Fab")
		)
		(fp_line
			(start -0.67945 0.3048)
			(end -0.67945 -0.305054)
			(stroke
				(width 0.1)
				(type default)
			)
			(layer "F.Fab")
		)
		(fp_line
			(start -0.12065 -0.305054)
			(end -0.12065 -0.2794)
			(stroke
				(width 0.1)
				(type default)
			)
			(layer "F.Fab")
		)
		(fp_line
			(start -0.12065 -0.2794)
			(end 0.12065 -0.2794)
			(stroke
				(width 0.1)
				(type default)
			)
			(layer "F.Fab")
		)
		(fp_line
			(start -0.12065 0.2794)
			(end -0.12065 0.3048)
			(stroke
				(width 0.1)
				(type default)
			)
			(layer "F.Fab")
		)
		(fp_line
			(start -0.12065 0.3048)
			(end -0.67945 0.3048)
			(stroke
				(width 0.1)
				(type default)
			)
			(layer "F.Fab")
		)
		(fp_line
			(start 0.120396 0.2794)
			(end -0.12065 0.2794)
			(stroke
				(width 0.1)
				(type default)
			)
			(layer "F.Fab")
		)
		(fp_line
			(start 0.120396 0.3048)
			(end 0.120396 0.2794)
			(stroke
				(width 0.1)
				(type default)
			)
			(layer "F.Fab")
		)
		(fp_line
			(start 0.12065 -0.3048)
			(end 0.67945 -0.3048)
			(stroke
				(width 0.1)
				(type default)
			)
			(layer "F.Fab")
		)
		(fp_line
			(start 0.12065 -0.2794)
			(end 0.12065 -0.3048)
			(stroke
				(width 0.1)
				(type default)
			)
			(layer "F.Fab")
		)
		(fp_line
			(start 0.67945 -0.3048)
			(end 0.67945 0.3048)
			(stroke
				(width 0.1)
				(type default)
			)
			(layer "F.Fab")
		)
		(fp_line
			(start 0.67945 0.3048)
			(end 0.120396 0.3048)
			(stroke
				(width 0.1)
				(type default)
			)
			(layer "F.Fab")
		)
		(pad "1" smd circle
			(at -0.40005 0)
			(size 0 0)
			(layers "F.Cu" "F.Mask" "F.Paste")
			(net "SW_PVDDCR_CPU0_P0_SW6")
		)
		(pad "2" smd circle
			(at 0.40005 0)
			(size 0 0)
			(layers "F.Cu" "F.Mask" "F.Paste")
			(net "SW_PVDDCR_CPU0_P0_SW6_RC")
		)
	)
	(footprint ""
		(layer "F.Cu")
		(at 71.663814 -145.801588 180)
		(property "Reference" "PC6006"
			(at 0 0 180)
			(layer "F.SilkS")
			(hide yes)
			(effects
				(font
					(size 1.27 1.27)
				)
			)
		)
		(property "Value" ""
			(at 0 0 180)
			(layer "F.Fab")
			(effects
				(font
					(size 1.27 1.27)
				)
			)
		)
		(duplicate_pad_numbers_are_jumpers no)
		(fp_line
			(start 0.7874 0.4064)
			(end -0.7874 0.4064)
			(stroke
				(width 0.1524)
				(type default)
			)
			(layer "F.SilkS")
		)
		(fp_line
			(start 0.7874 -0.4064)
			(end 0.7874 0.4064)
			(stroke
				(width 0.1524)
				(type default)
			)
			(layer "F.SilkS")
		)
		(fp_line
			(start -0.7874 0.4064)
			(end -0.7874 -0.4064)
			(stroke
				(width 0.1524)
				(type default)
			)
			(layer "F.SilkS")
		)
		(fp_line
			(start -0.7874 -0.4064)
			(end 0.7874 -0.4064)
			(stroke
				(width 0.1524)
				(type default)
			)
			(layer "F.SilkS")
		)
		(fp_line
			(start 0.67945 0.3048)
			(end 0.120396 0.3048)
			(stroke
				(width 0.1)
				(type default)
			)
			(layer "F.Fab")
		)
		(fp_line
			(start 0.67945 -0.3048)
			(end 0.67945 0.3048)
			(stroke
				(width 0.1)
				(type default)
			)
			(layer "F.Fab")
		)
		(fp_line
			(start 0.12065 -0.2794)
			(end 0.12065 -0.3048)
			(stroke
				(width 0.1)
				(type default)
			)
			(layer "F.Fab")
		)
		(fp_line
			(start 0.12065 -0.3048)
			(end 0.67945 -0.3048)
			(stroke
				(width 0.1)
				(type default)
			)
			(layer "F.Fab")
		)
		(fp_line
			(start 0.120396 0.3048)
			(end 0.120396 0.2794)
			(stroke
				(width 0.1)
				(type default)
			)
			(layer "F.Fab")
		)
		(fp_line
			(start 0.120396 0.2794)
			(end -0.12065 0.2794)
			(stroke
				(width 0.1)
				(type default)
			)
			(layer "F.Fab")
		)
		(fp_line
			(start -0.12065 0.3048)
			(end -0.67945 0.3048)
			(stroke
				(width 0.1)
				(type default)
			)
			(layer "F.Fab")
		)
		(fp_line
			(start -0.12065 0.2794)
			(end -0.12065 0.3048)
			(stroke
				(width 0.1)
				(type default)
			)
			(layer "F.Fab")
		)
		(fp_line
			(start -0.12065 -0.2794)
			(end 0.12065 -0.2794)
			(stroke
				(width 0.1)
				(type default)
			)
			(layer "F.Fab")
		)
		(fp_line
			(start -0.12065 -0.305054)
			(end -0.12065 -0.2794)
			(stroke
				(width 0.1)
				(type default)
			)
			(layer "F.Fab")
		)
		(fp_line
			(start -0.67945 0.3048)
			(end -0.67945 -0.305054)
			(stroke
				(width 0.1)
				(type default)
			)
			(layer "F.Fab")
		)
		(fp_line
			(start -0.67945 -0.305054)
			(end -0.12065 -0.305054)
			(stroke
				(width 0.1)
				(type default)
			)
			(layer "F.Fab")
		)
		(pad "1" smd circle
			(at -0.40005 0 180)
			(size 0 0)
			(layers "F.Cu" "F.Mask" "F.Paste")
			(net "PVDD18_S5_P1_FB_RC")
		)
		(pad "2" smd circle
			(at 0.40005 0 180)
			(size 0 0)
			(layers "F.Cu" "F.Mask" "F.Paste")
			(net "PVDD18_SS_P1_RGND")
		)
	)
)
